(kicad_pcb
	(version 20241229)
	(generator "pcbnew")
	(generator_version "9.0")
	(general
		(thickness 1.6296)
		(legacy_teardrops no)
	)
	(paper "A3")
	(title_block
		(title "Thunderbolt to 10GbE adapter")
		(date "2026-04-21")
		(rev "1.1.0")
		(company "Antmicro Ltd")
		(comment 1 "www.antmicro.com")
		(comment 9 "footprints 492-496 of 703")
	)
	(layers
		(0 "F.Cu" signal)
		(4 "In1.Cu" signal)
		(6 "In2.Cu" signal)
		(8 "In3.Cu" signal)
		(10 "In4.Cu" signal)
		(12 "In5.Cu" signal)
		(14 "In6.Cu" signal)
		(2 "B.Cu" signal)
		(9 "F.Adhes" user "F.Adhesive")
		(11 "B.Adhes" user "B.Adhesive")
		(13 "F.Paste" user)
		(15 "B.Paste" user)
		(5 "F.SilkS" user "F.Silkscreen")
		(7 "B.SilkS" user "B.Silkscreen")
		(1 "F.Mask" user)
		(3 "B.Mask" user)
		(17 "Dwgs.User" user "User.Drawings")
		(19 "Cmts.User" user "User.Comments")
		(21 "Eco1.User" user "User.Eco1")
		(23 "Eco2.User" user "User.Eco2")
		(25 "Edge.Cuts" user)
		(27 "Margin" user)
		(31 "F.CrtYd" user "F.Courtyard")
		(29 "B.CrtYd" user "B.Courtyard")
		(35 "F.Fab" user)
		(33 "B.Fab" user)
	)
	(footprint "antmicro-footprints:R_0402_1005Metric"
		(layer "B.Cu")
		(at 150.58 146.66 90)
		(descr "Resistor SMD 0402")
		(tags "resistor SMD 0402")
		(property "Reference" "R212"
			(at -1.09 0.42 270)
			(layer "B.SilkS")
			(effects
				(font
					(size 0.7 0.7)
					(thickness 0.15)
				)
				(justify left bottom mirror)
			)
		)
		(property "Value" "R_220R_0402"
			(at -1.011843 -1.772047 270)
			(layer "B.Fab")
			(effects
				(font
					(size 0.7 0.7)
					(thickness 0.15)
				)
				(justify left bottom mirror)
			)
		)
		(property "Datasheet" "https://www.bourns.com/docs/product-datasheets/cr.pdf"
			(at 0 0 270)
			(layer "B.Fab")
			(hide yes)
			(effects
				(font
					(size 1.27 1.27)
					(thickness 0.15)
				)
				(justify mirror)
			)
		)
		(property "Description" "SMD Chip Resistor, 220 ohm, ± 1%, 62.5 mW, 0402 [1005 Metric], Thick Film, General Purpose"
			(at 0 0 270)
			(layer "B.Fab")
			(hide yes)
			(effects
				(font
					(size 1.27 1.27)
					(thickness 0.15)
				)
				(justify mirror)
			)
		)
		(property "MPN" "CR0402-FX-2200GLF"
			(at 0 0 90)
			(unlocked yes)
			(layer "B.Fab")
			(hide yes)
			(effects
				(font
					(size 1 1)
					(thickness 0.15)
				)
				(justify mirror)
			)
		)
		(property "Manufacturer" "Bourns"
			(at 0 0 90)
			(unlocked yes)
			(layer "B.Fab")
			(hide yes)
			(effects
				(font
					(size 1 1)
					(thickness 0.15)
				)
				(justify mirror)
			)
		)
		(property "License" "Apache-2.0"
			(at 0 0 90)
			(unlocked yes)
			(layer "B.Fab")
			(hide yes)
			(effects
				(font
					(size 1 1)
					(thickness 0.15)
				)
				(justify mirror)
			)
		)
		(property "Author" "Antmicro"
			(at 0 0 90)
			(unlocked yes)
			(layer "B.Fab")
			(hide yes)
			(effects
				(font
					(size 1 1)
					(thickness 0.15)
				)
				(justify mirror)
			)
		)
		(property "Val" "220R"
			(at 0 0 90)
			(unlocked yes)
			(layer "B.Fab")
			(hide yes)
			(effects
				(font
					(size 1 1)
					(thickness 0.15)
				)
				(justify mirror)
			)
		)
		(property "Tolerance" "1%"
			(at 0 0 90)
			(unlocked yes)
			(layer "B.Fab")
			(hide yes)
			(effects
				(font
					(size 1 1)
					(thickness 0.15)
				)
				(justify mirror)
			)
		)
		(sheetname "/2xRJ45/")
		(sheetfile "2xrj45.kicad_sch")
		(attr smd)
		(fp_rect
			(start -0.925 0.47)
			(end 0.925 -0.47)
			(stroke
				(width 0.05)
				(type default)
			)
			(fill no)
			(layer "B.CrtYd")
		)
		(fp_rect
			(start -0.5 0.25)
			(end 0.5 -0.25)
			(stroke
				(width 0.15)
				(type solid)
			)
			(fill no)
			(layer "B.Fab")
		)
		(fp_text user "License: Apache-2.0"
			(at -0.95 -5.169 270)
			(layer "B.Fab")
			(effects
				(font
					(size 0.7 0.7)
					(thickness 0.15)
				)
				(justify left bottom mirror)
			)
		)
		(fp_text user "Author: Antmicro"
			(at -0.95 -4.169 270)
			(layer "B.Fab")
			(effects
				(font
					(size 0.7 0.7)
					(thickness 0.15)
				)
				(justify left bottom mirror)
			)
		)
		(fp_text user "${REFERENCE}"
			(at -0.95 -3.168 270)
			(layer "B.Fab")
			(effects
				(font
					(size 0.7 0.7)
					(thickness 0.15)
				)
				(justify left bottom mirror)
			)
		)
		(pad "1" smd roundrect
			(at -0.48 0 90)
			(size 0.59 0.64)
			(layers "B.Cu" "B.Mask" "B.Paste")
			(roundrect_rratio 0.25)
			(net 410 "Net-(J3-LED_GRN-)")
			(pintype "passive")
		)
		(pad "2" smd roundrect
			(at 0.48 0 90)
			(size 0.59 0.64)
			(layers "B.Cu" "B.Mask" "B.Paste")
			(roundrect_rratio 0.25)
			(net 61 "/2xRJ45/~{P0_LED_ACT}")
			(pintype "passive")
		)
	)
	(footprint "antmicro-footprints:C_0402_1005Metric"
		(layer "B.Cu")
		(at 149.681866 92.485117 90)
		(descr "Capacitor SMD 0402")
		(tags "capacitor SMD 0402")
		(property "Reference" "C279"
			(at -10.814884 18.718134 270)
			(layer "B.SilkS")
			(effects
				(font
					(size 0.7 0.7)
					(thickness 0.15)
				)
				(justify mirror)
			)
		)
		(property "Value" "C_1u_25V_0402"
			(at -1.022927 -2.155213 270)
			(layer "B.Fab")
			(effects
				(font
					(size 0.7 0.7)
					(thickness 0.15)
				)
				(justify left bottom mirror)
			)
		)
		(property "Datasheet" "https://www.murata.com/products/productdetail?partno=GRM155R61E105KE11%23"
			(at 0 0 270)
			(layer "B.Fab")
			(hide yes)
			(effects
				(font
					(size 1.27 1.27)
					(thickness 0.15)
				)
				(justify mirror)
			)
		)
		(property "Description" "SMD Multilayer Ceramic Capacitor, 1 µF, 25 V, 0402 [1005 Metric], ± 10%, X5R, GRM Series"
			(at 0 0 270)
			(layer "B.Fab")
			(hide yes)
			(effects
				(font
					(size 1.27 1.27)
					(thickness 0.15)
				)
				(justify mirror)
			)
		)
		(property "MPN" "GRM155R61E105KE11J"
			(at 0 0 90)
			(unlocked yes)
			(layer "B.Fab")
			(hide yes)
			(effects
				(font
					(size 1 1)
					(thickness 0.15)
				)
				(justify mirror)
			)
		)
		(property "Manufacturer" "Murata"
			(at 0 0 90)
			(unlocked yes)
			(layer "B.Fab")
			(hide yes)
			(effects
				(font
					(size 1 1)
					(thickness 0.15)
				)
				(justify mirror)
			)
		)
		(property "License" "Apache-2.0"
			(at 0 0 90)
			(unlocked yes)
			(layer "B.Fab")
			(hide yes)
			(effects
				(font
					(size 1 1)
					(thickness 0.15)
				)
				(justify mirror)
			)
		)
		(property "Author" "Antmicro"
			(at 0 0 90)
			(unlocked yes)
			(layer "B.Fab")
			(hide yes)
			(effects
				(font
					(size 1 1)
					(thickness 0.15)
				)
				(justify mirror)
			)
		)
		(property "Val" "1u"
			(at 0 0 90)
			(unlocked yes)
			(layer "B.Fab")
			(hide yes)
			(effects
				(font
					(size 1 1)
					(thickness 0.15)
				)
				(justify mirror)
			)
		)
		(property "Voltage" "25V"
			(at 0 0 90)
			(unlocked yes)
			(layer "B.Fab")
			(hide yes)
			(effects
				(font
					(size 1 1)
					(thickness 0.15)
				)
				(justify mirror)
			)
		)
		(property "Dielectric" "X5R"
			(at 0 0 90)
			(unlocked yes)
			(layer "B.Fab")
			(hide yes)
			(effects
				(font
					(size 1 1)
					(thickness 0.15)
				)
				(justify mirror)
			)
		)
		(sheetname "/X710-AT2 Misc/")
		(sheetfile "x710-at2-mics.kicad_sch")
		(attr smd)
		(fp_rect
			(start -0.925 0.47)
			(end 0.925 -0.47)
			(stroke
				(width 0.05)
				(type default)
			)
			(fill no)
			(layer "B.CrtYd")
		)
		(fp_line
			(start 0.504 -0.248)
			(end -0.494 -0.248)
			(stroke
				(width 0.15)
				(type solid)
			)
			(layer "B.Fab")
		)
		(fp_line
			(start -0.494 -0.248)
			(end -0.494 0.25)
			(stroke
				(width 0.15)
				(type solid)
			)
			(layer "B.Fab")
		)
		(fp_line
			(start 0.504 0.25)
			(end 0.504 -0.248)
			(stroke
				(width 0.15)
				(type solid)
			)
			(layer "B.Fab")
		)
		(fp_line
			(start -0.494 0.25)
			(end 0.504 0.25)
			(stroke
				(width 0.15)
				(type solid)
			)
			(layer "B.Fab")
		)
		(fp_text user "Author: Antmicro"
			(at -0.939 -3.399 270)
			(layer "B.Fab")
			(effects
				(font
					(size 0.7 0.7)
					(thickness 0.15)
				)
				(justify left bottom mirror)
			)
		)
		(fp_text user "${REFERENCE}"
			(at -0.939 -4.599 270)
			(layer "B.Fab")
			(effects
				(font
					(size 0.7 0.7)
					(thickness 0.15)
				)
				(justify left bottom mirror)
			)
		)
		(fp_text user "License: Apache-2.0"
			(at -0.939 -5.799 270)
			(layer "B.Fab")
			(effects
				(font
					(size 0.7 0.7)
					(thickness 0.15)
				)
				(justify left bottom mirror)
			)
		)
		(pad "1" smd roundrect
			(at -0.48 0 90)
			(size 0.59 0.64)
			(layers "B.Cu" "B.Mask" "B.Paste")
			(roundrect_rratio 0.25)
			(net 23 "GND")
			(pintype "passive")
		)
		(pad "2" smd roundrect
			(at 0.48 0 90)
			(size 0.59 0.64)
			(layers "B.Cu" "B.Mask" "B.Paste")
			(roundrect_rratio 0.25)
			(net 35 "/X710-AT2 Misc/POR_BYPASS")
			(pintype "passive")
		)
	)
	(footprint "antmicro-footprints:C_0402_1005Metric"
		(layer "B.Cu")
		(at 154.261866 85.265117 180)
		(descr "Capacitor SMD 0402")
		(tags "capacitor SMD 0402")
		(property "Reference" "C207"
			(at -17.938134 -9.464883 0)
			(layer "B.SilkS")
			(effects
				(font
					(size 0.7 0.7)
					(thickness 0.15)
				)
				(justify mirror)
			)
		)
		(property "Value" "C_1u_25V_0402"
			(at -1.022927 -2.155213 0)
			(layer "B.Fab")
			(effects
				(font
					(size 0.7 0.7)
					(thickness 0.15)
				)
				(justify left bottom mirror)
			)
		)
		(property "Datasheet" "https://www.murata.com/products/productdetail?partno=GRM155R61E105KE11%23"
			(at 0 0 0)
			(layer "B.Fab")
			(hide yes)
			(effects
				(font
					(size 1.27 1.27)
					(thickness 0.15)
				)
				(justify mirror)
			)
		)
		(property "Description" "SMD Multilayer Ceramic Capacitor, 1 µF, 25 V, 0402 [1005 Metric], ± 10%, X5R, GRM Series"
			(at 0 0 0)
			(layer "B.Fab")
			(hide yes)
			(effects
				(font
					(size 1.27 1.27)
					(thickness 0.15)
				)
				(justify mirror)
			)
		)
		(property "MPN" "GRM155R61E105KE11J"
			(at 0 0 180)
			(unlocked yes)
			(layer "B.Fab")
			(hide yes)
			(effects
				(font
					(size 1 1)
					(thickness 0.15)
				)
				(justify mirror)
			)
		)
		(property "Manufacturer" "Murata"
			(at 0 0 180)
			(unlocked yes)
			(layer "B.Fab")
			(hide yes)
			(effects
				(font
					(size 1 1)
					(thickness 0.15)
				)
				(justify mirror)
			)
		)
		(property "License" "Apache-2.0"
			(at 0 0 180)
			(unlocked yes)
			(layer "B.Fab")
			(hide yes)
			(effects
				(font
					(size 1 1)
					(thickness 0.15)
				)
				(justify mirror)
			)
		)
		(property "Author" "Antmicro"
			(at 0 0 180)
			(unlocked yes)
			(layer "B.Fab")
			(hide yes)
			(effects
				(font
					(size 1 1)
					(thickness 0.15)
				)
				(justify mirror)
			)
		)
		(property "Val" "1u"
			(at 0 0 180)
			(unlocked yes)
			(layer "B.Fab")
			(hide yes)
			(effects
				(font
					(size 1 1)
					(thickness 0.15)
				)
				(justify mirror)
			)
		)
		(property "Voltage" "25V"
			(at 0 0 180)
			(unlocked yes)
			(layer "B.Fab")
			(hide yes)
			(effects
				(font
					(size 1 1)
					(thickness 0.15)
				)
				(justify mirror)
			)
		)
		(property "Dielectric" "X5R"
			(at 0 0 180)
			(unlocked yes)
			(layer "B.Fab")
			(hide yes)
			(effects
				(font
					(size 1 1)
					(thickness 0.15)
				)
				(justify mirror)
			)
		)
		(sheetname "/X710-AT2 power/")
		(sheetfile "x710-at2-power.kicad_sch")
		(attr smd)
		(fp_rect
			(start -0.925 0.47)
			(end 0.925 -0.47)
			(stroke
				(width 0.05)
				(type default)
			)
			(fill no)
			(layer "B.CrtYd")
		)
		(fp_line
			(start 0.504 0.25)
			(end 0.504 -0.248)
			(stroke
				(width 0.15)
				(type solid)
			)
			(layer "B.Fab")
		)
		(fp_line
			(start 0.504 -0.248)
			(end -0.494 -0.248)
			(stroke
				(width 0.15)
				(type solid)
			)
			(layer "B.Fab")
		)
		(fp_line
			(start -0.494 0.25)
			(end 0.504 0.25)
			(stroke
				(width 0.15)
				(type solid)
			)
			(layer "B.Fab")
		)
		(fp_line
			(start -0.494 -0.248)
			(end -0.494 0.25)
			(stroke
				(width 0.15)
				(type solid)
			)
			(layer "B.Fab")
		)
		(fp_text user "Author: Antmicro"
			(at -0.939 -3.399 0)
			(layer "B.Fab")
			(effects
				(font
					(size 0.7 0.7)
					(thickness 0.15)
				)
				(justify left bottom mirror)
			)
		)
		(fp_text user "${REFERENCE}"
			(at -0.939 -4.599 0)
			(layer "B.Fab")
			(effects
				(font
					(size 0.7 0.7)
					(thickness 0.15)
				)
				(justify left bottom mirror)
			)
		)
		(fp_text user "License: Apache-2.0"
			(at -0.939 -5.799 0)
			(layer "B.Fab")
			(effects
				(font
					(size 0.7 0.7)
					(thickness 0.15)
				)
				(justify left bottom mirror)
			)
		)
		(pad "1" smd roundrect
			(at -0.48 0 180)
			(size 0.59 0.64)
			(layers "B.Cu" "B.Mask" "B.Paste")
			(roundrect_rratio 0.25)
			(net 23 "GND")
			(pintype "passive")
		)
		(pad "2" smd roundrect
			(at 0.48 0 180)
			(size 0.59 0.64)
			(layers "B.Cu" "B.Mask" "B.Paste")
			(roundrect_rratio 0.25)
			(net 12 "XFI_VDD")
			(pintype "passive")
		)
	)
	(footprint "antmicro-footprints:C_0402_1005Metric"
		(layer "B.Cu")
		(at 145.631866 78.260118 180)
		(descr "Capacitor SMD 0402")
		(tags "capacitor SMD 0402")
		(property "Reference" "C259"
			(at -17.768134 -9.464883 0)
			(layer "B.SilkS")
			(effects
				(font
					(size 0.7 0.7)
					(thickness 0.15)
				)
				(justify mirror)
			)
		)
		(property "Value" "C_1u_25V_0402"
			(at -1.022927 -2.155213 0)
			(layer "B.Fab")
			(effects
				(font
					(size 0.7 0.7)
					(thickness 0.15)
				)
				(justify left bottom mirror)
			)
		)
		(property "Datasheet" "https://www.murata.com/products/productdetail?partno=GRM155R61E105KE11%23"
			(at 0 0 0)
			(layer "B.Fab")
			(hide yes)
			(effects
				(font
					(size 1.27 1.27)
					(thickness 0.15)
				)
				(justify mirror)
			)
		)
		(property "Description" "SMD Multilayer Ceramic Capacitor, 1 µF, 25 V, 0402 [1005 Metric], ± 10%, X5R, GRM Series"
			(at 0 0 0)
			(layer "B.Fab")
			(hide yes)
			(effects
				(font
					(size 1.27 1.27)
					(thickness 0.15)
				)
				(justify mirror)
			)
		)
		(property "MPN" "GRM155R61E105KE11J"
			(at 0 0 180)
			(unlocked yes)
			(layer "B.Fab")
			(hide yes)
			(effects
				(font
					(size 1 1)
					(thickness 0.15)
				)
				(justify mirror)
			)
		)
		(property "Manufacturer" "Murata"
			(at 0 0 180)
			(unlocked yes)
			(layer "B.Fab")
			(hide yes)
			(effects
				(font
					(size 1 1)
					(thickness 0.15)
				)
				(justify mirror)
			)
		)
		(property "License" "Apache-2.0"
			(at 0 0 180)
			(unlocked yes)
			(layer "B.Fab")
			(hide yes)
			(effects
				(font
					(size 1 1)
					(thickness 0.15)
				)
				(justify mirror)
			)
		)
		(property "Author" "Antmicro"
			(at 0 0 180)
			(unlocked yes)
			(layer "B.Fab")
			(hide yes)
			(effects
				(font
					(size 1 1)
					(thickness 0.15)
				)
				(justify mirror)
			)
		)
		(property "Val" "1u"
			(at 0 0 180)
			(unlocked yes)
			(layer "B.Fab")
			(hide yes)
			(effects
				(font
					(size 1 1)
					(thickness 0.15)
				)
				(justify mirror)
			)
		)
		(property "Voltage" "25V"
			(at 0 0 180)
			(unlocked yes)
			(layer "B.Fab")
			(hide yes)
			(effects
				(font
					(size 1 1)
					(thickness 0.15)
				)
				(justify mirror)
			)
		)
		(property "Dielectric" "X5R"
			(at 0 0 180)
			(unlocked yes)
			(layer "B.Fab")
			(hide yes)
			(effects
				(font
					(size 1 1)
					(thickness 0.15)
				)
				(justify mirror)
			)
		)
		(sheetname "/X710-AT2 power/")
		(sheetfile "x710-at2-power.kicad_sch")
		(attr smd)
		(fp_rect
			(start -0.925 0.47)
			(end 0.925 -0.47)
			(stroke
				(width 0.05)
				(type default)
			)
			(fill no)
			(layer "B.CrtYd")
		)
		(fp_line
			(start 0.504 0.25)
			(end 0.504 -0.248)
			(stroke
				(width 0.15)
				(type solid)
			)
			(layer "B.Fab")
		)
		(fp_line
			(start 0.504 -0.248)
			(end -0.494 -0.248)
			(stroke
				(width 0.15)
				(type solid)
			)
			(layer "B.Fab")
		)
		(fp_line
			(start -0.494 0.25)
			(end 0.504 0.25)
			(stroke
				(width 0.15)
				(type solid)
			)
			(layer "B.Fab")
		)
		(fp_line
			(start -0.494 -0.248)
			(end -0.494 0.25)
			(stroke
				(width 0.15)
				(type solid)
			)
			(layer "B.Fab")
		)
		(fp_text user "${REFERENCE}"
			(at -0.939 -4.599 0)
			(layer "B.Fab")
			(effects
				(font
					(size 0.7 0.7)
					(thickness 0.15)
				)
				(justify left bottom mirror)
			)
		)
		(fp_text user "License: Apache-2.0"
			(at -0.939 -5.799 0)
			(layer "B.Fab")
			(effects
				(font
					(size 0.7 0.7)
					(thickness 0.15)
				)
				(justify left bottom mirror)
			)
		)
		(fp_text user "Author: Antmicro"
			(at -0.939 -3.399 0)
			(layer "B.Fab")
			(effects
				(font
					(size 0.7 0.7)
					(thickness 0.15)
				)
				(justify left bottom mirror)
			)
		)
		(pad "1" smd roundrect
			(at -0.48 0 180)
			(size 0.59 0.64)
			(layers "B.Cu" "B.Mask" "B.Paste")
			(roundrect_rratio 0.25)
			(net 23 "GND")
			(pintype "passive")
		)
		(pad "2" smd roundrect
			(at 0.48 0 180)
			(size 0.59 0.64)
			(layers "B.Cu" "B.Mask" "B.Paste")
			(roundrect_rratio 0.25)
			(net 1 "VCCA")
			(pintype "passive")
		)
	)
	(footprint "antmicro-footprints:R_0402_1005Metric"
		(layer "B.Cu")
		(at 136.5 122.15)
		(descr "Resistor SMD 0402")
		(tags "resistor SMD 0402")
		(property "Reference" "R53"
			(at 19.525001 -7.450001 180)
			(layer "B.SilkS")
			(effects
				(font
					(size 0.7 0.7)
					(thickness 0.15)
				)
				(justify mirror)
			)
		)
		(property "Value" "R_100k_0402"
			(at -1.011843 -1.772047 180)
			(layer "B.Fab")
			(effects
				(font
					(size 0.7 0.7)
					(thickness 0.15)
				)
				(justify left bottom mirror)
			)
		)
		(property "Datasheet" "https://www.bourns.com/docs/product-datasheets/cr.pdf"
			(at 0 0 180)
			(layer "B.Fab")
			(hide yes)
			(effects
				(font
					(size 1.27 1.27)
					(thickness 0.15)
				)
				(justify mirror)
			)
		)
		(property "Description" "SMD Chip Resistor, 100 kohm, ± 1%, 62.5 mW, 0402 [1005 Metric], Thick Film, General Purpose"
			(at 0 0 180)
			(layer "B.Fab")
			(hide yes)
			(effects
				(font
					(size 1.27 1.27)
					(thickness 0.15)
				)
				(justify mirror)
			)
		)
		(property "MPN" "CR0402-FX-1003GLF"
			(at 0 0 0)
			(unlocked yes)
			(layer "B.Fab")
			(hide yes)
			(effects
				(font
					(size 1 1)
					(thickness 0.15)
				)
				(justify mirror)
			)
		)
		(property "Manufacturer" "Bourns"
			(at 0 0 0)
			(unlocked yes)
			(layer "B.Fab")
			(hide yes)
			(effects
				(font
					(size 1 1)
					(thickness 0.15)
				)
				(justify mirror)
			)
		)
		(property "License" "Apache-2.0"
			(at 0 0 0)
			(unlocked yes)
			(layer "B.Fab")
			(hide yes)
			(effects
				(font
					(size 1 1)
					(thickness 0.15)
				)
				(justify mirror)
			)
		)
		(property "Val" "100k"
			(at 0 0 0)
			(unlocked yes)
			(layer "B.Fab")
			(hide yes)
			(effects
				(font
					(size 1 1)
					(thickness 0.15)
				)
				(justify mirror)
			)
		)
		(property "Tolerance" "1%"
			(at 0 0 0)
			(unlocked yes)
			(layer "B.Fab")
			(hide yes)
			(effects
				(font
					(size 1 1)
					(thickness 0.15)
				)
				(justify mirror)
			)
		)
		(property "Author" "Antmicro"
			(at 0 0 0)
			(unlocked yes)
			(layer "B.Fab")
			(hide yes)
			(effects
				(font
					(size 1 1)
					(thickness 0.15)
				)
				(justify mirror)
			)
		)
		(sheetname "/TB Controller/")
		(sheetfile "tb.kicad_sch")
		(attr smd)
		(fp_rect
			(start -0.925 0.47)
			(end 0.925 -0.47)
			(stroke
				(width 0.05)
				(type default)
			)
			(fill no)
			(layer "B.CrtYd")
		)
		(fp_rect
			(start -0.5 0.25)
			(end 0.5 -0.25)
			(stroke
				(width 0.15)
				(type solid)
			)
			(fill no)
			(layer "B.Fab")
		)
		(fp_text user "Author: Antmicro"
			(at -0.95 -4.169 180)
			(layer "B.Fab")
			(effects
				(font
					(size 0.7 0.7)
					(thickness 0.15)
				)
				(justify left bottom mirror)
			)
		)
		(fp_text user "License: Apache-2.0"
			(at -0.95 -5.169 180)
			(layer "B.Fab")
			(effects
				(font
					(size 0.7 0.7)
					(thickness 0.15)
				)
				(justify left bottom mirror)
			)
		)
		(fp_text user "${REFERENCE}"
			(at -0.95 -3.168 180)
			(layer "B.Fab")
			(effects
				(font
					(size 0.7 0.7)
					(thickness 0.15)
				)
				(justify left bottom mirror)
			)
		)
		(pad "1" smd roundrect
			(at -0.48 0)
			(size 0.59 0.64)
			(layers "B.Cu" "B.Mask" "B.Paste")
			(roundrect_rratio 0.25)
			(net 236 "Net-(U4C-POC_GPIO_6)")
			(pintype "passive")
		)
		(pad "2" smd roundrect
			(at 0.48 0)
			(size 0.59 0.64)
			(layers "B.Cu" "B.Mask" "B.Paste")
			(roundrect_rratio 0.25)
			(net 23 "GND")
			(pintype "passive")
		)
	)
)
